# Lightning_PDPB_EQL.xlsx — PCIE_TX_1027 (si-constraints)
|  |  | Group | Pin | NET1 | NET2 | NET3 | NET4 | NET5 | Length (NET1) | <1mils  match (NET1) | Length (NET2) | <1mils  match (NET2) | Length (NET3) | <1mils  match (NET3) | Length (NET4) | <1mils  match (NET4) | Length (NET5) | <1mils  match (NET5) | Unnecessary trace | Total Length | mils Bundle Length match | <1mils  Total Length match | <2000mils  Pair to pair Length match | Note |
|  |  | 1_J17 | A5 | PE_TX1_DR1_n |  |  |  |  | 9310.35 | OK |  | OK |  | OK |  | OK |  | OK |  | 9310.35 | OK | OK | OK |  |
|  |  |  | A6 | PE_TX1_DR1_p |  |  |  |  | 9310.06 |  |  |  |  |  |  |  |  |  |  | 9310.06 |  |  |  |  |
|  |  |  | A9 | PE_TX2_DR1_n |  |  |  |  | 9071.08 | OK |  | OK |  | OK |  | OK |  | OK |  | 9071.08 |  | OK |  |  |
|  |  |  | A10 | PE_TX2_DR1_p |  |  |  |  | 9071.1 |  |  |  |  |  |  |  |  |  |  | 9071.1 |  |  |  |  |
| DPB SPEC |  |  | A13 | PE_TX3_DR1_n |  |  |  |  | 9008.67 | OK |  | OK |  | OK |  | OK |  | OK |  | 9008.67 | OK | OK |  |  |
| PCIE max length | 16inch |  | A14 | PE_TX3_DR1_p |  |  |  |  | 9008.66 |  |  |  |  |  |  |  |  |  |  | 9008.66 |  |  |  |  |
| +/- match (Segment) NET1 | 1mil |  | A17 | PE_TX4_DR1_n |  |  |  |  | 8974.0400000000009 | OK |  | OK |  | OK |  | OK |  | OK |  | 8974.0400000000009 |  | OK |  |  |
| +/- match (Segment) NET2 | 1mil |  | A18 | PE_TX4_DR1_p |  |  |  |  | 8974.0400000000009 |  |  |  |  |  |  |  |  |  |  | 8974.0400000000009 |  |  |  |  |
|  |  |  | A24 | PE_TX1_DR10_p |  |  |  |  | 3700.77 | OK |  | OK |  | OK |  | OK |  | OK |  | 3700.77 | OK | OK | OK |  |
|  |  |  | A25 | PE_TX1_DR10_n |  |  |  |  | 3700.84 |  |  |  |  |  |  |  |  |  |  | 3700.84 |  |  |  |  |
|  |  |  | A28 | PE_TX2_DR10_p |  |  |  |  | 3154.31 | OK |  | OK |  | OK |  | OK |  | OK |  | 3154.31 |  | OK |  |  |
|  |  |  | A29 | PE_TX2_DR10_n |  |  |  |  | 3154.16 |  |  |  |  |  |  |  |  |  |  | 3154.16 |  |  |  |  |
|  |  |  | A32 | PE_TX3_DR10_p |  |  |  |  | 2929.45 | OK |  | OK |  | OK |  | OK |  | OK |  | 2929.45 | OK | OK |  |  |
|  |  |  | A33 | PE_TX3_DR10_n |  |  |  |  | 2929.6 |  |  |  |  |  |  |  |  |  |  | 2929.6 |  |  |  |  |
|  |  |  | A36 | PE_TX4_DR10_p |  |  |  |  | 2673.07 | OK |  | OK |  | OK |  | OK |  | OK |  | 2673.07 |  | OK |  |  |
|  |  |  | A37 | PE_TX4_DR10_n |  |  |  |  | 2673.15 |  |  |  |  |  |  |  |  |  |  | 2673.15 |  |  |  |  |
|  |  |  | A40 | PE_TX1_DR0_n |  |  |  |  | 10237.549999999999 | OK |  | OK |  | OK |  | OK |  | OK |  | 10237.549999999999 | OK | OK | OK |  |
|  |  |  | A41 | PE_TX1_DR0_p |  |  |  |  | 10237.469999999999 |  |  |  |  |  |  |  |  |  |  | 10237.469999999999 |  |  |  |  |
|  |  |  | A48 | PE_TX2_DR0_n |  |  |  |  | 10090.61 | OK |  | OK |  | OK |  | OK |  | OK |  | 10090.61 |  | OK |  |  |
|  |  |  | A49 | PE_TX2_DR0_p |  |  |  |  | 10090.709999999999 |  |  |  |  |  |  |  |  |  |  | 10090.709999999999 |  |  |  |  |
|  |  |  | A52 | PE_TX3_DR0_n |  |  |  |  | 10190.1 | OK |  | OK |  | OK |  | OK |  | OK |  | 10190.1 | OK | OK |  |  |
|  |  |  | A53 | PE_TX3_DR0_p |  |  |  |  | 10190.34 |  |  |  |  |  |  |  |  |  |  | 10190.34 |  |  |  |  |
|  |  |  | A56 | PE_TX4_DR0_n |  |  |  |  | 10373.02 | OK |  | OK |  | OK |  | OK |  | OK |  | 10373.02 |  | OK |  |  |
|  |  |  | A57 | PE_TX4_DR0_p |  |  |  |  | 10372.61 |  |  |  |  |  |  |  |  |  |  | 10372.61 |  |  |  |  |
|  |  |  | A63 | PE_TX1_DR5_p |  |  |  |  | 2348.75 | OK |  | OK |  | OK |  | OK |  | OK |  | 2348.75 | OK | OK | OK |  |
|  |  |  | A64 | PE_TX1_DR5_n |  |  |  |  | 2348.2800000000002 |  |  |  |  |  |  |  |  |  |  | 2348.2800000000002 |  |  |  |  |
|  |  |  | A67 | PE_TX2_DR5_p |  |  |  |  | 2609.71 | OK |  | OK |  | OK |  | OK |  | OK |  | 2609.71 |  | OK |  |  |
|  |  |  | A68 | PE_TX2_DR5_n |  |  |  |  | 2609 |  |  |  |  |  |  |  |  |  |  | 2609 |  |  |  |  |
|  |  |  | A71 | PE_TX3_DR5_p |  |  |  |  | 2580.5700000000002 | OK |  | OK |  | OK |  | OK |  | OK |  | 2580.5700000000002 | OK | OK |  |  |
|  |  |  | A72 | PE_TX3_DR5_n |  |  |  |  | 2579.8000000000002 |  |  |  |  |  |  |  |  |  |  | 2579.8000000000002 |  |  |  |  |
|  |  |  | A75 | PE_TX4_DR5_p |  |  |  |  | 2601.0100000000002 | OK |  | OK |  | OK |  | OK |  | OK |  | 2601.0100000000002 |  | OK |  |  |
|  |  |  | A76 | PE_TX4_DR5_n |  |  |  |  | 2600.2399999999998 |  |  |  |  |  |  |  |  |  |  | 2600.2399999999998 |  |  |  |  |
|  |  | 2_J18 | A2 | PE_TX3_DR4_n |  |  |  |  | 12489.01 | OK |  | OK |  | OK |  | OK |  | OK |  | 12489.01 | OK | OK | OK | Same group with 3_J19 A91,92,95,96 |
|  |  |  | A3 | PE_TX3_DR4_p |  |  |  |  | 12488.12 |  |  |  |  |  |  |  |  |  |  | 12488.12 |  |  |  |  |
|  |  |  | A6 | PE_TX4_DR4_n |  |  |  |  | 12493.92 | OK |  | OK |  | OK |  | OK |  | OK |  | 12493.92 |  | OK |  |  |
|  |  |  | A7 | PE_TX4_DR4_p |  |  |  |  | 12493.64 |  |  |  |  |  |  |  |  |  |  | 12493.64 |  |  |  |  |
|  |  |  | A14 | PE_TX1_DR3_n |  |  |  |  | 11068.14 | OK |  | OK |  | OK |  | OK |  | OK |  | 11068.14 | OK | OK | OK |  |
|  |  |  | A15 | PE_TX1_DR3_p |  |  |  |  | 11068.01 |  |  |  |  |  |  |  |  |  |  | 11068.01 |  |  |  |  |
|  |  |  | A18 | PE_TX2_DR3_n |  |  |  |  | 11051.2 | OK |  | OK |  | OK |  | OK |  | OK |  | 11051.2 |  | OK |  |  |
|  |  |  | A19 | PE_TX2_DR3_p |  |  |  |  | 11051.22 |  |  |  |  |  |  |  |  |  |  | 11051.22 |  |  |  |  |
|  |  |  | A22 | PE_TX3_DR3_n |  |  |  |  | 11070.82 | OK |  | OK |  | OK |  | OK |  | OK |  | 11070.82 | OK | OK |  |  |
|  |  |  | A23 | PE_TX3_DR3_p |  |  |  |  | 11070.89 |  |  |  |  |  |  |  |  |  |  | 11070.89 |  |  |  |  |
|  |  |  | A26 | PE_TX4_DR3_n |  |  |  |  | 11080.07 | OK |  | OK |  | OK |  | OK |  | OK |  | 11080.07 |  | OK |  |  |
|  |  |  | A27 | PE_TX4_DR3_p |  |  |  |  | 11080.03 |  |  |  |  |  |  |  |  |  |  | 11080.03 |  |  |  |  |
|  |  |  | A30 | PE_TX1_DR7_n |  |  |  |  | 2443.6 | OK |  | OK |  | OK |  | OK |  | OK |  | 2443.6 | OK | OK | OK |  |
|  |  |  | A31 | PE_TX1_DR7_p |  |  |  |  | 2443.6 |  |  |  |  |  |  |  |  |  |  | 2443.6 |  |  |  |  |
|  |  |  | A34 | PE_TX2_DR7_n |  |  |  |  | 2072.41 | OK |  | OK |  | OK |  | OK |  | OK |  | 2072.41 |  | OK |  |  |
|  |  |  | A35 | PE_TX2_DR7_p |  |  |  |  | 2072.4299999999998 |  |  |  |  |  |  |  |  |  |  | 2072.4299999999998 |  |  |  |  |
|  |  |  | A38 | PE_TX3_DR7_n |  |  |  |  | 2041.73 | OK |  | OK |  | OK |  | OK |  | OK |  | 2041.73 | OK | OK |  |  |
|  |  |  | A39 | PE_TX3_DR7_p |  |  |  |  | 2041.74 |  |  |  |  |  |  |  |  |  |  | 2041.74 |  |  |  |  |
|  |  |  | A42 | PE_TX4_DR7_n |  |  |  |  | 1995.57 | OK |  | OK |  | OK |  | OK |  | OK |  | 1995.57 |  | OK |  |  |
|  |  |  | A43 | PE_TX4_DR7_p |  |  |  |  | 1995.57 |  |  |  |  |  |  |  |  |  |  | 1995.57 |  |  |  |  |
|  |  |  | A48 | PE_TX1_DR2_n |  |  |  |  | 9469.5 | OK |  | OK |  | OK |  | OK |  | OK |  | 9469.5 | OK | OK | OK |  |
|  |  |  | A49 | PE_TX1_DR2_p |  |  |  |  | 9469.5 |  |  |  |  |  |  |  |  |  |  | 9469.5 |  |  |  |  |
|  |  |  | A52 | PE_TX2_DR2_n |  |  |  |  | 9545.4699999999993 | OK |  | OK |  | OK |  | OK |  | OK |  | 9545.4699999999993 |  | OK |  |  |
|  |  |  | A53 | PE_TX2_DR2_p |  |  |  |  | 9545.4500000000007 |  |  |  |  |  |  |  |  |  |  | 9545.4500000000007 |  |  |  |  |
|  |  |  | A56 | PE_TX3_DR2_n |  |  |  |  | 9627.23 | OK |  | OK |  | OK |  | OK |  | OK |  | 9627.23 | OK | OK |  |  |
|  |  |  | A57 | PE_TX3_DR2_p |  |  |  |  | 9627.23 |  |  |  |  |  |  |  |  |  |  | 9627.23 |  |  |  |  |
|  |  |  | A60 | PE_TX4_DR2_n |  |  |  |  | 9698.26 | OK |  | OK |  | OK |  | OK |  | OK |  | 9698.26 |  | OK |  |  |
|  |  |  | A61 | PE_TX4_DR2_p |  |  |  |  | 9698.23 |  |  |  |  |  |  |  |  |  |  | 9698.23 |  |  |  |  |
|  |  |  | A67 | PE_TX1_DR11_n |  |  |  |  | 1770.02 | OK |  | OK |  | OK |  | OK |  | OK |  | 1770.02 | OK | OK | OK |  |
|  |  |  | A68 | PE_TX1_DR11_p |  |  |  |  | 1770.09 |  |  |  |  |  |  |  |  |  |  | 1770.09 |  |  |  |  |
|  |  |  | A71 | PE_TX2_DR11_n |  |  |  |  | 2296.17 | OK |  | OK |  | OK |  | OK |  | OK |  | 2296.17 |  | OK |  |  |
|  |  |  | A72 | PE_TX2_DR11_p |  |  |  |  | 2296.29 |  |  |  |  |  |  |  |  |  |  | 2296.29 |  |  |  |  |
|  |  |  | A75 | PE_TX3_DR11_n |  |  |  |  | 2657.73 | OK |  | OK |  | OK |  | OK |  | OK |  | 2657.73 | OK | OK |  |  |
|  |  |  | A76 | PE_TX3_DR11_p |  |  |  |  | 2657.78 |  |  |  |  |  |  |  |  |  |  | 2657.78 |  |  |  |  |
|  |  |  | A79 | PE_TX4_DR11_n |  |  |  |  | 2957.11 | OK |  | OK |  | OK |  | OK |  | OK |  | 2957.11 |  | OK |  |  |
|  |  |  | A80 | PE_TX4_DR11_p |  |  |  |  | 2956.79 |  |  |  |  |  |  |  |  |  |  | 2956.79 |  |  |  |  |
|  |  |  | A83 | PE_TX1_DR6_n |  |  |  |  | 1791.55 | OK |  | OK |  | OK |  | OK |  | OK |  | 1791.55 | OK | OK | OK |  |
|  |  |  | A84 | PE_TX1_DR6_p |  |  |  |  | 1791.56 |  |  |  |  |  |  |  |  |  |  | 1791.56 |  |  |  |  |
|  |  |  | A87 | PE_TX2_DR6_n |  |  |  |  | 2419.59 | OK |  | OK |  | OK |  | OK |  | OK |  | 2419.59 |  | OK |  |  |
|  |  |  | A88 | PE_TX2_DR6_p |  |  |  |  | 2419.65 |  |  |  |  |  |  |  |  |  |  | 2419.65 |  |  |  |  |
|  |  |  | A91 | PE_TX3_DR6_n |  |  |  |  | 2301.71 | OK |  | OK |  | OK |  | OK |  | OK |  | 2301.71 | OK | OK |  |  |
|  |  |  | A92 | PE_TX3_DR6_p |  |  |  |  | 2301.71 |  |  |  |  |  |  |  |  |  |  | 2301.71 |  |  |  |  |
|  |  |  | A95 | PE_TX4_DR6_n |  |  |  |  | 2244.44 | OK |  | OK |  | OK |  | OK |  | OK |  | 2244.44 |  | OK |  |  |
|  |  |  | A96 | PE_TX4_DR6_p |  |  |  |  | 2244.4299999999998 |  |  |  |  |  |  |  |  |  |  | 2244.4299999999998 |  |  |  |  |
|  |  | 3_J19 | A2 | PE_TX1_DR14_n |  |  |  |  | 5307.64 | OK |  | OK |  | OK |  | OK |  | OK |  | 5307.64 | OK | OK | OK |  |
|  |  |  | A3 | PE_TX1_DR14_p |  |  |  |  | 5307.54 |  |  |  |  |  |  |  |  |  |  | 5307.54 |  |  |  |  |
|  |  |  | A6 | PE_TX2_DR14_n |  |  |  |  | 6012.78 | OK |  | OK |  | OK |  | OK |  | OK |  | 6012.78 |  | OK |  |  |
|  |  |  | A7 | PE_TX2_DR14_p |  |  |  |  | 6013.23 |  |  |  |  |  |  |  |  |  |  | 6013.23 |  |  |  |  |
|  |  |  | A10 | PE_TX3_DR14_n |  |  |  |  | 6317.21 | OK |  | OK |  | OK |  | OK |  | OK |  | 6317.21 | OK | OK |  |  |
|  |  |  | A11 | PE_TX3_DR14_p |  |  |  |  | 6317.11 |  |  |  |  |  |  |  |  |  |  | 6317.11 |  |  |  |  |
|  |  |  | A14 | PE_TX4_DR14_n |  |  |  |  | 6664.18 | OK |  | OK |  | OK |  | OK |  | OK |  | 6664.18 |  | OK |  |  |
|  |  |  | A15 | PE_TX4_DR14_p |  |  |  |  | 6664.19 |  |  |  |  |  |  |  |  |  |  | 6664.19 |  |  |  |  |
|  |  |  | A22 | PE_TX1_DR13_n |  |  |  |  | 2074.4499999999998 | OK |  | OK |  | OK |  | OK |  | OK |  | 2074.4499999999998 | OK | OK | OK |  |
|  |  |  | A23 | PE_TX1_DR13_p |  |  |  |  | 2074.4899999999998 |  |  |  |  |  |  |  |  |  |  | 2074.4899999999998 |  |  |  |  |
|  |  |  | A26 | PE_TX2_DR13_n |  |  |  |  | 2721.55 | OK |  | OK |  | OK |  | OK |  | OK |  | 2721.55 |  | OK |  |  |
|  |  |  | A27 | PE_TX2_DR13_p |  |  |  |  | 2721.58 |  |  |  |  |  |  |  |  |  |  | 2721.58 |  |  |  |  |
|  |  |  | A30 | PE_TX3_DR13_n |  |  |  |  | 3089.45 | OK |  | OK |  | OK |  | OK |  | OK |  | 3089.45 | OK | OK |  |  |
|  |  |  | A31 | PE_TX3_DR13_p |  |  |  |  | 3089.47 |  |  |  |  |  |  |  |  |  |  | 3089.47 |  |  |  |  |
|  |  |  | A34 | PE_TX4_DR13_n |  |  |  |  | 3443.56 | OK |  | OK |  | OK |  | OK |  | OK |  | 3443.56 |  | OK |  |  |
|  |  |  | A35 | PE_TX4_DR13_p |  |  |  |  | 3443.49 |  |  |  |  |  |  |  |  |  |  | 3443.49 |  |  |  |  |
|  |  |  | A38 | PE_TX1_DR9_n |  |  |  |  | 6818.65 | OK |  | OK |  | OK |  | OK |  | OK |  | 6818.65 | OK | OK | OK |  |
|  |  |  | A39 | PE_TX1_DR9_p |  |  |  |  | 6818.66 |  |  |  |  |  |  |  |  |  |  | 6818.66 |  |  |  |  |
|  |  |  | A42 | PE_TX2_DR9_n |  |  |  |  | 6464.39 | OK |  | OK |  | OK |  | OK |  | OK |  | 6464.39 |  | OK |  |  |
|  |  |  | A43 | PE_TX2_DR9_p |  |  |  |  | 6464.39 |  |  |  |  |  |  |  |  |  |  | 6464.39 |  |  |  |  |
|  |  |  | A48 | PE_TX3_DR9_n |  |  |  |  | 6514.93 | OK |  | OK |  | OK |  | OK |  | OK |  | 6514.93 | OK | OK |  |  |
|  |  |  | A49 | PE_TX3_DR9_p |  |  |  |  | 6514.93 |  |  |  |  |  |  |  |  |  |  | 6514.93 |  |  |  |  |
|  |  |  | A52 | PE_TX4_DR9_n |  |  |  |  | 6487.35 | OK |  | OK |  | OK |  | OK |  | OK |  | 6487.35 |  | OK |  |  |
|  |  |  | A53 | PE_TX4_DR9_p |  |  |  |  | 6487.28 |  |  |  |  |  |  |  |  |  |  | 6487.28 |  |  |  |  |
|  |  |  | A59 | PE_TX1_DR8_n |  |  |  |  | 2543.7399999999998 | OK |  | OK |  | OK |  | OK |  | OK |  | 2543.7399999999998 | OK | OK | OK |  |
|  |  |  | A60 | PE_TX1_DR8_p |  |  |  |  | 2543.7399999999998 |  |  |  |  |  |  |  |  |  |  | 2543.7399999999998 |  |  |  |  |
|  |  |  | A63 | PE_TX2_DR8_n |  |  |  |  | 2171.15 | OK |  | OK |  | OK |  | OK |  | OK |  | 2171.15 |  | OK |  |  |
|  |  |  | A64 | PE_TX2_DR8_p |  |  |  |  | 2171.17 |  |  |  |  |  |  |  |  |  |  | 2171.17 |  |  |  |  |
|  |  |  | A67 | PE_TX3_DR8_n |  |  |  |  | 2142.13 | OK |  | OK |  | OK |  | OK |  | OK |  | 2142.13 | OK | OK |  |  |
|  |  |  | A68 | PE_TX3_DR8_p |  |  |  |  | 2142.14 |  |  |  |  |  |  |  |  |  |  | 2142.14 |  |  |  |  |
|  |  |  | A71 | PE_TX4_DR8_n |  |  |  |  | 2121.09 | OK |  | OK |  | OK |  | OK |  | OK |  | 2121.09 |  | OK |  |  |
|  |  |  | A72 | PE_TX4_DR8_p |  |  |  |  | 2121.09 |  |  |  |  |  |  |  |  |  |  | 2121.09 |  |  |  |  |
|  |  |  | A75 | PE_TX1_DR12_n |  |  |  |  | 4091.77 | OK |  | OK |  | OK |  | OK |  | OK |  | 4091.77 | OK | OK | OK |  |
|  |  |  | A76 | PE_TX1_DR12_p |  |  |  |  | 4091.73 |  |  |  |  |  |  |  |  |  |  | 4091.73 |  |  |  |  |
|  |  |  | A79 | PE_TX2_DR12_n |  |  |  |  | 3622.09 | OK |  | OK |  | OK |  | OK |  | OK |  | 3622.09 |  | OK |  |  |
|  |  |  | A80 | PE_TX2_DR12_p |  |  |  |  | 3621.9 |  |  |  |  |  |  |  |  |  |  | 3621.9 |  |  |  |  |
|  |  |  | A83 | PE_TX3_DR12_n |  |  |  |  | 3455.21 | OK |  | OK |  | OK |  | OK |  | OK |  | 3455.21 | OK | OK |  |  |
|  |  |  | A84 | PE_TX3_DR12_p |  |  |  |  | 3455.05 |  |  |  |  |  |  |  |  |  |  | 3455.05 |  |  |  |  |
|  |  |  | A87 | PE_TX4_DR12_n |  |  |  |  | 3297.63 | OK |  | OK |  | OK |  | OK |  | OK |  | 3297.63 |  | OK |  |  |
|  |  |  | A88 | PE_TX4_DR12_p |  |  |  |  | 3297.16 |  |  |  |  |  |  |  |  |  |  | 3297.16 |  |  |  |  |
|  |  |  | A91 | PE_TX1_DR4_n |  |  |  |  | 12696.71 | OK |  | OK |  | OK |  | OK |  | OK |  | 12696.71 | OK | OK | OK | Same group with 2_J18 A2,3,6,7 |
|  |  |  | A92 | PE_TX1_DR4_p |  |  |  |  | 12696.61 |  |  |  |  |  |  |  |  |  |  | 12696.61 |  |  |  |  |
|  |  |  | A95 | PE_TX2_DR4_n |  |  |  |  | 12696.17 | OK |  | OK |  | OK |  | OK |  | OK |  | 12696.17 |  | OK |  |  |
|  |  |  | A96 | PE_TX2_DR4_p |  |  |  |  | 12696.16 |  |  |  |  |  |  |  |  |  |  | 12696.16 |  |  |  |  |
